# BASEBOARD_FAB2 (Tioga Pass) — schematic netlist excerpt (pin names and nets, part order shuffled) for the footprints in the layout excerpt that follows; sources: Cadence DE-HDL packaged netlist, KiCad conversion of Wiwynn_Tioga_Pass_MB.brd

C7A42  CAP  22UF 4V 20% X6S  pkg 0805LF  page 236 : A = P1V05_PCH_STBY ; B = GND
C7B15  CAP_A  22.0UF 4V 20% X6S  pkg 0603V  page 131 : A = P1V05_PCH_STBY ; B = GND
R4D41  RES  4.75K 1% CHIP  pkg 0402  page 102 : A = P3V3_DB1200 ; B = FM_HBW_BYPASS_LOWBW_N

(kicad_pcb
	(version 20260206)
	(generator "pcbnew")
	(generator_version "10.0")
	(general
		(thickness 1.6)
		(legacy_teardrops no)
	)
	(paper "A4")
	(title_block
		(title "Wiwynn_Tioga_Pass_MB.brd")
		(comment 1 "Tioga Pass / footprints 762-764 of 4770")
	)
	(layers
		(0 "F.Cu" signal "TOP")
		(4 "In1.Cu" signal "L2GND")
		(6 "In2.Cu" signal "L3")
		(8 "In3.Cu" signal "L4GND")
		(10 "In4.Cu" signal "L5")
		(12 "In5.Cu" signal "L6GND")
		(14 "In6.Cu" signal "L7VCC")
		(16 "In7.Cu" signal "L8VCC")
		(18 "In8.Cu" signal "L9GND")
		(20 "In9.Cu" signal "L10")
		(22 "In10.Cu" signal "L11GND")
		(24 "In11.Cu" signal "L12")
		(26 "In12.Cu" signal "L13GND")
		(2 "B.Cu" signal "BOTTOM")
		(9 "F.Adhes" user "F.Adhesive")
		(11 "B.Adhes" user "B.Adhesive")
		(13 "F.Paste" user "Package Geometry/Pastemask Top")
		(15 "B.Paste" user "Package Geometry/Pastemask Bottom")
		(5 "F.SilkS" user "Ref Des/Silkscreen Top")
		(7 "B.SilkS" user "Ref Des/Silkscreen Bottom")
		(1 "F.Mask" user "Board Geometry/Soldermask Top")
		(3 "B.Mask" user "Board Geometry/Soldermask Bottom")
		(17 "Dwgs.User" user "User.Drawings")
		(19 "Cmts.User" user "User.Comments")
		(21 "Eco1.User" user "User.Eco1")
		(23 "Eco2.User" user "User.Eco2")
		(25 "Edge.Cuts" user "Board Geometry/Outline")
		(27 "Margin" user)
		(31 "F.CrtYd" user "Package Geometry/Place Bound Top")
		(29 "B.CrtYd" user "Package Geometry/Place Bound Bottom")
		(35 "F.Fab" user "Ref Des/Assembly Top")
		(33 "B.Fab" user "Ref Des/Assembly Bottom")
	)
	(footprint ""
		(layer "F.Cu")
		(at 387.96976 -139.5222)
		(property "Reference" "C7A42"
			(at 0 0 0)
			(layer "F.SilkS")
			(hide yes)
			(effects
				(font
					(size 1.27 1.27)
				)
			)
		)
		(property "Value" ""
			(at 0 0 0)
			(layer "F.Fab")
			(effects
				(font
					(size 1.27 1.27)
				)
			)
		)
		(duplicate_pad_numbers_are_jumpers no)
		(fp_rect
			(start 0.7239 1.9939)
			(end -0.7239 -0.2159)
			(stroke
				(width 0)
				(type default)
			)
			(fill no)
			(layer "F.CrtYd")
		)
		(fp_line
			(start -0.7239 -0.2159)
			(end -0.7239 1.9939)
			(stroke
				(width 0.1)
				(type default)
			)
			(layer "F.Fab")
		)
		(fp_line
			(start -0.7239 1.9939)
			(end 0.7239 1.9939)
			(stroke
				(width 0.1)
				(type default)
			)
			(layer "F.Fab")
		)
		(fp_line
			(start 0.7239 -0.2159)
			(end -0.7239 -0.2159)
			(stroke
				(width 0.1)
				(type default)
			)
			(layer "F.Fab")
		)
		(fp_line
			(start 0.7239 1.9939)
			(end 0.7239 -0.2159)
			(stroke
				(width 0.1)
				(type default)
			)
			(layer "F.Fab")
		)
		(pad "1" smd rect
			(at 0 0)
			(size 1.27 1.016)
			(layers "F.Cu" "F.Mask" "F.Paste")
			(net "P1V05_PCH_STBY")
		)
		(pad "2" smd rect
			(at 0 1.778)
			(size 1.27 1.016)
			(layers "F.Cu" "F.Mask" "F.Paste")
			(net "GND")
		)
		(zone
			(layer "F.Cu")
			(hatch none 0.5)
			(connect_pads
				(clearance 0)
			)
			(min_thickness 0.25)
			(keepout
				(tracks not_allowed)
				(vias allowed)
				(pads allowed)
				(copperpour not_allowed)
				(footprints allowed)
			)
			(placement
				(enabled no)
				(sheetname "")
			)
			(fill
				(thermal_gap 0.5)
				(thermal_bridge_width 0.5)
				(island_removal_mode 0)
			)
			(polygon
				(pts
					(xy 388.60476 -138.2522) (xy 388.60476 -139.0142) (xy 387.33476 -139.0142) (xy 387.33476 -138.2522)
				)
			)
		)
	)
	(footprint ""
		(layer "F.Cu")
		(at 386.45338 -140.14704 -90)
		(property "Reference" "C7B15"
			(at 0 0 270)
			(layer "F.SilkS")
			(hide yes)
			(effects
				(font
					(size 1.27 1.27)
				)
			)
		)
		(property "Value" ""
			(at 0 0 270)
			(layer "F.Fab")
			(effects
				(font
					(size 1.27 1.27)
				)
			)
		)
		(duplicate_pad_numbers_are_jumpers no)
		(fp_rect
			(start -0.4953 1.6002)
			(end 0.4953 -0.2032)
			(stroke
				(width 0)
				(type default)
			)
			(fill no)
			(layer "F.CrtYd")
		)
		(fp_line
			(start -0.4953 1.6002)
			(end -0.4953 -0.2032)
			(stroke
				(width 0.1)
				(type default)
			)
			(layer "F.Fab")
		)
		(fp_line
			(start 0.4953 1.6002)
			(end -0.4953 1.6002)
			(stroke
				(width 0.1)
				(type default)
			)
			(layer "F.Fab")
		)
		(fp_line
			(start -0.4953 -0.2032)
			(end 0.4953 -0.2032)
			(stroke
				(width 0.1)
				(type default)
			)
			(layer "F.Fab")
		)
		(fp_line
			(start 0.4953 -0.2032)
			(end 0.4953 1.6002)
			(stroke
				(width 0.1)
				(type default)
			)
			(layer "F.Fab")
		)
		(pad "1" smd rect
			(at 0 0 270)
			(size 0.762 0.889)
			(layers "F.Cu" "F.Mask" "F.Paste")
			(net "P1V05_PCH_STBY")
		)
		(pad "2" smd rect
			(at 0 1.397 270)
			(size 0.762 0.889)
			(layers "F.Cu" "F.Mask" "F.Paste")
			(net "GND")
		)
		(zone
			(layer "F.Cu")
			(hatch none 0.5)
			(connect_pads
				(clearance 0)
			)
			(min_thickness 0.25)
			(keepout
				(tracks not_allowed)
				(vias allowed)
				(pads allowed)
				(copperpour not_allowed)
				(footprints allowed)
			)
			(placement
				(enabled no)
				(sheetname "")
			)
			(fill
				(thermal_gap 0.5)
				(thermal_bridge_width 0.5)
				(island_removal_mode 0)
			)
			(polygon
				(pts
					(xy 385.50088 -140.52804) (xy 385.50088 -139.76604) (xy 386.00888 -139.76604) (xy 386.00888 -140.52804)
				)
			)
		)
	)
	(footprint ""
		(layer "F.Cu")
		(at 167.294052 -73.056242 180)
		(property "Reference" "R4D41"
			(at 0 0 180)
			(layer "F.SilkS")
			(hide yes)
			(effects
				(font
					(size 1.27 1.27)
				)
			)
		)
		(property "Value" ""
			(at 0 0 180)
			(layer "F.Fab")
			(effects
				(font
					(size 1.27 1.27)
				)
			)
		)
		(duplicate_pad_numbers_are_jumpers no)
		(fp_poly
			(pts
				(xy -0.2794 -0.1016) (xy 0.2794 -0.1016) (xy 0.2794 0.9906) (xy -0.2794 0.9906)
			)
			(stroke
				(width 0)
				(type default)
			)
			(fill no)
			(layer "F.CrtYd")
		)
		(fp_line
			(start 0.2794 0.9906)
			(end 0.2794 -0.1016)
			(stroke
				(width 0.1)
				(type default)
			)
			(layer "F.Fab")
		)
		(fp_line
			(start 0.2794 -0.1016)
			(end -0.2794 -0.1016)
			(stroke
				(width 0.1)
				(type default)
			)
			(layer "F.Fab")
		)
		(fp_line
			(start -0.2794 0.9906)
			(end 0.2794 0.9906)
			(stroke
				(width 0.1)
				(type default)
			)
			(layer "F.Fab")
		)
		(fp_line
			(start -0.2794 -0.1016)
			(end -0.2794 0.9906)
			(stroke
				(width 0.1)
				(type default)
			)
			(layer "F.Fab")
		)
		(pad "1" smd rect
			(at 0 0 180)
			(size 0.508 0.508)
			(layers "F.Cu" "F.Mask" "F.Paste")
			(net "P3V3_DB1200")
		)
		(pad "2" smd rect
			(at 0 0.889 180)
			(size 0.508 0.508)
			(layers "F.Cu" "F.Mask" "F.Paste")
			(net "FM_HBW_BYPASS_LOWBW_N")
		)
		(zone
			(layer "F.Cu")
			(hatch none 0.5)
			(connect_pads
				(clearance 0)
			)
			(min_thickness 0.25)
			(keepout
				(tracks not_allowed)
				(vias allowed)
				(pads allowed)
				(copperpour not_allowed)
				(footprints allowed)
			)
			(placement
				(enabled no)
				(sheetname "")
			)
			(fill
				(thermal_gap 0.5)
				(thermal_bridge_width 0.5)
				(island_removal_mode 0)
			)
			(polygon
				(pts
					(xy 167.548052 -73.691242) (xy 167.040052 -73.691242) (xy 167.040052 -73.310242) (xy 167.548052 -73.310242)
				)
			)
		)
		(zone
			(layer "F.Cu")
			(hatch none 0.5)
			(connect_pads
				(clearance 0)
			)
			(min_thickness 0.25)
			(keepout
				(tracks allowed)
				(vias not_allowed)
				(pads allowed)
				(copperpour not_allowed)
				(footprints allowed)
			)
			(placement
				(enabled no)
				(sheetname "")
			)
			(fill
				(thermal_gap 0.5)
				(thermal_bridge_width 0.5)
				(island_removal_mode 0)
			)
			(polygon
				(pts
					(xy 167.548052 -73.310242) (xy 167.040052 -73.310242) (xy 167.040052 -73.691242) (xy 167.548052 -73.691242)
				)
			)
		)
	)
)
